(kicad_pcb
	(version 20260206)
	(generator "pcbnew")
	(generator_version "10.0")
	(general
		(thickness 1.6)
		(legacy_teardrops no)
	)
	(paper "A4")
	(title_block
		(title "04192023_DAF0TMB3IC0_F0TG_MB_C_brd_V02_OCP.brd")
		(comment 1 "Grand Teton / footprints 7391-7397 of 8354")
	)
	(layers
		(0 "F.Cu" signal "TOP")
		(4 "In1.Cu" signal "GND")
		(6 "In2.Cu" signal "IN1")
		(8 "In3.Cu" signal "GND1")
		(10 "In4.Cu" signal "IN2")
		(12 "In5.Cu" signal "GND2")
		(14 "In6.Cu" signal "IN3")
		(16 "In7.Cu" signal "GND3")
		(18 "In8.Cu" signal "VCC")
		(20 "In9.Cu" signal "VCC1")
		(22 "In10.Cu" signal "GND4")
		(24 "In11.Cu" signal "IN4")
		(26 "In12.Cu" signal "GND5")
		(28 "In13.Cu" signal "IN5")
		(30 "In14.Cu" signal "GND6")
		(32 "In15.Cu" signal "IN6")
		(34 "In16.Cu" signal "GND7")
		(2 "B.Cu" signal "BOTTOM")
		(9 "F.Adhes" user "F.Adhesive")
		(11 "B.Adhes" user "B.Adhesive")
		(13 "F.Paste" user "Package Geometry/Pastemask Top")
		(15 "B.Paste" user "Package Geometry/Pastemask Bottom")
		(5 "F.SilkS" user "Ref Des/Silkscreen Top")
		(7 "B.SilkS" user "Ref Des/Silkscreen Bottom")
		(1 "F.Mask" user "Board Geometry/Soldermask Top")
		(3 "B.Mask" user "Board Geometry/Soldermask Bottom")
		(17 "Dwgs.User" user "User.Drawings")
		(19 "Cmts.User" user "User.Comments")
		(21 "Eco1.User" user "User.Eco1")
		(23 "Eco2.User" user "User.Eco2")
		(25 "Edge.Cuts" user "Board Geometry/Outline")
		(27 "Margin" user)
		(31 "F.CrtYd" user "Package Geometry/Place Bound Top")
		(29 "B.CrtYd" user "Package Geometry/Place Bound Bottom")
		(35 "F.Fab" user "Ref Des/Assembly Top")
		(33 "B.Fab" user "Ref Des/Assembly Bottom")
	)
	(footprint ""
		(layer "B.Cu")
		(at 206.22133 -194.98691)
		(property "Reference" "R1591"
			(at 0 0 0)
			(layer "B.SilkS")
			(hide yes)
			(effects
				(font
					(size 1.27 1.27)
				)
				(justify mirror)
			)
		)
		(property "Value" ""
			(at 0 0 0)
			(layer "B.Fab")
			(effects
				(font
					(size 1.27 1.27)
				)
				(justify mirror)
			)
		)
		(duplicate_pad_numbers_are_jumpers no)
		(fp_line
			(start -0.7874 -0.4064)
			(end -0.7874 0.4064)
			(stroke
				(width 0.1524)
				(type default)
			)
			(layer "B.SilkS")
		)
		(fp_line
			(start -0.7874 0.4064)
			(end 0.7874 0.4064)
			(stroke
				(width 0.1524)
				(type default)
			)
			(layer "B.SilkS")
		)
		(fp_line
			(start 0.7874 -0.4064)
			(end -0.7874 -0.4064)
			(stroke
				(width 0.1524)
				(type default)
			)
			(layer "B.SilkS")
		)
		(fp_line
			(start 0.7874 0.4064)
			(end 0.7874 -0.4064)
			(stroke
				(width 0.1524)
				(type default)
			)
			(layer "B.SilkS")
		)
		(fp_line
			(start -0.67945 -0.3048)
			(end -0.67945 0.3048)
			(stroke
				(width 0.1)
				(type default)
			)
			(layer "B.Fab")
		)
		(fp_line
			(start -0.67945 0.3048)
			(end -0.120396 0.3048)
			(stroke
				(width 0.1)
				(type default)
			)
			(layer "B.Fab")
		)
		(fp_line
			(start -0.12065 -0.3048)
			(end -0.67945 -0.3048)
			(stroke
				(width 0.1)
				(type default)
			)
			(layer "B.Fab")
		)
		(fp_line
			(start -0.12065 -0.2794)
			(end -0.12065 -0.3048)
			(stroke
				(width 0.1)
				(type default)
			)
			(layer "B.Fab")
		)
		(fp_line
			(start -0.120396 0.2794)
			(end 0.12065 0.2794)
			(stroke
				(width 0.1)
				(type default)
			)
			(layer "B.Fab")
		)
		(fp_line
			(start -0.120396 0.3048)
			(end -0.120396 0.2794)
			(stroke
				(width 0.1)
				(type default)
			)
			(layer "B.Fab")
		)
		(fp_line
			(start 0.12065 -0.305054)
			(end 0.12065 -0.2794)
			(stroke
				(width 0.1)
				(type default)
			)
			(layer "B.Fab")
		)
		(fp_line
			(start 0.12065 -0.2794)
			(end -0.12065 -0.2794)
			(stroke
				(width 0.1)
				(type default)
			)
			(layer "B.Fab")
		)
		(fp_line
			(start 0.12065 0.2794)
			(end 0.12065 0.3048)
			(stroke
				(width 0.1)
				(type default)
			)
			(layer "B.Fab")
		)
		(fp_line
			(start 0.12065 0.3048)
			(end 0.67945 0.3048)
			(stroke
				(width 0.1)
				(type default)
			)
			(layer "B.Fab")
		)
		(fp_line
			(start 0.67945 -0.305054)
			(end 0.12065 -0.305054)
			(stroke
				(width 0.1)
				(type default)
			)
			(layer "B.Fab")
		)
		(fp_line
			(start 0.67945 0.3048)
			(end 0.67945 -0.305054)
			(stroke
				(width 0.1)
				(type default)
			)
			(layer "B.Fab")
		)
		(pad "1" smd circle
			(at 0.40005 0 180)
			(size 0 0)
			(layers "B.Cu" "B.Mask" "B.Paste")
			(net "I3C_SPD_DDRGL_CPU1_SCL")
		)
		(pad "2" smd circle
			(at -0.40005 0 180)
			(size 0 0)
			(layers "B.Cu" "B.Mask" "B.Paste")
			(net "I3C_SPD_DDRL_CPU1_SCL")
		)
	)
	(footprint ""
		(layer "B.Cu")
		(at 113.959386 -266.005564)
		(property "Reference" "C2275"
			(at 0 0 0)
			(layer "B.SilkS")
			(hide yes)
			(effects
				(font
					(size 1.27 1.27)
				)
				(justify mirror)
			)
		)
		(property "Value" ""
			(at 0 0 0)
			(layer "B.Fab")
			(effects
				(font
					(size 1.27 1.27)
				)
				(justify mirror)
			)
		)
		(duplicate_pad_numbers_are_jumpers no)
		(fp_line
			(start -0.7874 -0.4064)
			(end -0.7874 0.4064)
			(stroke
				(width 0.1524)
				(type default)
			)
			(layer "B.SilkS")
		)
		(fp_line
			(start -0.7874 0.4064)
			(end 0.7874 0.4064)
			(stroke
				(width 0.1524)
				(type default)
			)
			(layer "B.SilkS")
		)
		(fp_line
			(start 0.7874 -0.4064)
			(end -0.7874 -0.4064)
			(stroke
				(width 0.1524)
				(type default)
			)
			(layer "B.SilkS")
		)
		(fp_line
			(start 0.7874 0.4064)
			(end 0.7874 -0.4064)
			(stroke
				(width 0.1524)
				(type default)
			)
			(layer "B.SilkS")
		)
		(fp_line
			(start -0.67945 -0.3048)
			(end -0.67945 0.3048)
			(stroke
				(width 0.1)
				(type default)
			)
			(layer "B.Fab")
		)
		(fp_line
			(start -0.67945 0.3048)
			(end -0.120396 0.3048)
			(stroke
				(width 0.1)
				(type default)
			)
			(layer "B.Fab")
		)
		(fp_line
			(start -0.12065 -0.3048)
			(end -0.67945 -0.3048)
			(stroke
				(width 0.1)
				(type default)
			)
			(layer "B.Fab")
		)
		(fp_line
			(start -0.12065 -0.2794)
			(end -0.12065 -0.3048)
			(stroke
				(width 0.1)
				(type default)
			)
			(layer "B.Fab")
		)
		(fp_line
			(start -0.120396 0.2794)
			(end 0.12065 0.2794)
			(stroke
				(width 0.1)
				(type default)
			)
			(layer "B.Fab")
		)
		(fp_line
			(start -0.120396 0.3048)
			(end -0.120396 0.2794)
			(stroke
				(width 0.1)
				(type default)
			)
			(layer "B.Fab")
		)
		(fp_line
			(start 0.12065 -0.305054)
			(end 0.12065 -0.2794)
			(stroke
				(width 0.1)
				(type default)
			)
			(layer "B.Fab")
		)
		(fp_line
			(start 0.12065 -0.2794)
			(end -0.12065 -0.2794)
			(stroke
				(width 0.1)
				(type default)
			)
			(layer "B.Fab")
		)
		(fp_line
			(start 0.12065 0.2794)
			(end 0.12065 0.3048)
			(stroke
				(width 0.1)
				(type default)
			)
			(layer "B.Fab")
		)
		(fp_line
			(start 0.12065 0.3048)
			(end 0.67945 0.3048)
			(stroke
				(width 0.1)
				(type default)
			)
			(layer "B.Fab")
		)
		(fp_line
			(start 0.67945 -0.305054)
			(end 0.12065 -0.305054)
			(stroke
				(width 0.1)
				(type default)
			)
			(layer "B.Fab")
		)
		(fp_line
			(start 0.67945 0.3048)
			(end 0.67945 -0.305054)
			(stroke
				(width 0.1)
				(type default)
			)
			(layer "B.Fab")
		)
		(pad "1" smd circle
			(at 0.40005 0 180)
			(size 0 0)
			(layers "B.Cu" "B.Mask" "B.Paste")
			(net "PVDD11_S3_P1")
		)
		(pad "2" smd circle
			(at -0.40005 0 180)
			(size 0 0)
			(layers "B.Cu" "B.Mask" "B.Paste")
			(net "GND")
		)
	)
	(footprint ""
		(layer "B.Cu")
		(at 127.319024 -31.259272)
		(property "Reference" "C6066"
			(at 0 0 0)
			(layer "B.SilkS")
			(hide yes)
			(effects
				(font
					(size 1.27 1.27)
				)
				(justify mirror)
			)
		)
		(property "Value" ""
			(at 0 0 0)
			(layer "B.Fab")
			(effects
				(font
					(size 1.27 1.27)
				)
				(justify mirror)
			)
		)
		(duplicate_pad_numbers_are_jumpers no)
		(fp_line
			(start -1.2954 -0.5842)
			(end -1.2954 0.5842)
			(stroke
				(width 0.1524)
				(type default)
			)
			(layer "B.SilkS")
		)
		(fp_line
			(start -1.2954 0.5842)
			(end 1.2954 0.5842)
			(stroke
				(width 0.1524)
				(type default)
			)
			(layer "B.SilkS")
		)
		(fp_line
			(start 1.2954 -0.5842)
			(end -1.2954 -0.5842)
			(stroke
				(width 0.1524)
				(type default)
			)
			(layer "B.SilkS")
		)
		(fp_line
			(start 1.2954 0.5842)
			(end 1.2954 -0.5842)
			(stroke
				(width 0.1524)
				(type default)
			)
			(layer "B.SilkS")
		)
		(fp_line
			(start -1.1938 -0.4064)
			(end -1.1938 0.4064)
			(stroke
				(width 0.1)
				(type default)
			)
			(layer "B.Fab")
		)
		(fp_line
			(start -1.1938 0.4064)
			(end -0.8636 0.4064)
			(stroke
				(width 0.1)
				(type default)
			)
			(layer "B.Fab")
		)
		(fp_line
			(start -0.8636 -0.4572)
			(end -0.8636 -0.4064)
			(stroke
				(width 0.1)
				(type default)
			)
			(layer "B.Fab")
		)
		(fp_line
			(start -0.8636 -0.4064)
			(end -1.1938 -0.4064)
			(stroke
				(width 0.1)
				(type default)
			)
			(layer "B.Fab")
		)
		(fp_line
			(start -0.8636 0.4064)
			(end -0.8636 0.4572)
			(stroke
				(width 0.1)
				(type default)
			)
			(layer "B.Fab")
		)
		(fp_line
			(start -0.8636 0.4572)
			(end 0.8636 0.4572)
			(stroke
				(width 0.1)
				(type default)
			)
			(layer "B.Fab")
		)
		(fp_line
			(start 0.8636 -0.4572)
			(end -0.8636 -0.4572)
			(stroke
				(width 0.1)
				(type default)
			)
			(layer "B.Fab")
		)
		(fp_line
			(start 0.8636 -0.4064)
			(end 0.8636 -0.4572)
			(stroke
				(width 0.1)
				(type default)
			)
			(layer "B.Fab")
		)
		(fp_line
			(start 0.8636 0.4064)
			(end 1.1938 0.4064)
			(stroke
				(width 0.1)
				(type default)
			)
			(layer "B.Fab")
		)
		(fp_line
			(start 0.8636 0.4572)
			(end 0.8636 0.4064)
			(stroke
				(width 0.1)
				(type default)
			)
			(layer "B.Fab")
		)
		(fp_line
			(start 1.1938 -0.4064)
			(end 0.8636 -0.4064)
			(stroke
				(width 0.1)
				(type default)
			)
			(layer "B.Fab")
		)
		(fp_line
			(start 1.1938 0.4064)
			(end 1.1938 -0.4064)
			(stroke
				(width 0.1)
				(type default)
			)
			(layer "B.Fab")
		)
		(pad "1" smd rect
			(at 0.7366 0 270)
			(size 0.7112 0.8128)
			(layers "B.Cu" "B.Mask" "B.Paste")
			(net "P1V2_AUX")
		)
		(pad "2" smd rect
			(at -0.7366 0 270)
			(size 0.7112 0.8128)
			(layers "B.Cu" "B.Mask" "B.Paste")
			(net "GND")
		)
	)
	(footprint ""
		(layer "B.Cu")
		(at 128.811528 -40.106092 180)
		(property "Reference" "C6071"
			(at 0 0 0)
			(layer "B.SilkS")
			(hide yes)
			(effects
				(font
					(size 1.27 1.27)
				)
				(justify mirror)
			)
		)
		(property "Value" ""
			(at 0 0 0)
			(layer "B.Fab")
			(effects
				(font
					(size 1.27 1.27)
				)
				(justify mirror)
			)
		)
		(duplicate_pad_numbers_are_jumpers no)
		(fp_line
			(start 0.7874 0.4064)
			(end 0.7874 -0.4064)
			(stroke
				(width 0.1524)
				(type default)
			)
			(layer "B.SilkS")
		)
		(fp_line
			(start 0.7874 -0.4064)
			(end -0.7874 -0.4064)
			(stroke
				(width 0.1524)
				(type default)
			)
			(layer "B.SilkS")
		)
		(fp_line
			(start -0.7874 0.4064)
			(end 0.7874 0.4064)
			(stroke
				(width 0.1524)
				(type default)
			)
			(layer "B.SilkS")
		)
		(fp_line
			(start -0.7874 -0.4064)
			(end -0.7874 0.4064)
			(stroke
				(width 0.1524)
				(type default)
			)
			(layer "B.SilkS")
		)
		(fp_line
			(start 0.67945 0.3048)
			(end 0.67945 -0.305054)
			(stroke
				(width 0.1)
				(type default)
			)
			(layer "B.Fab")
		)
		(fp_line
			(start 0.67945 -0.305054)
			(end 0.12065 -0.305054)
			(stroke
				(width 0.1)
				(type default)
			)
			(layer "B.Fab")
		)
		(fp_line
			(start 0.12065 0.3048)
			(end 0.67945 0.3048)
			(stroke
				(width 0.1)
				(type default)
			)
			(layer "B.Fab")
		)
		(fp_line
			(start 0.12065 0.2794)
			(end 0.12065 0.3048)
			(stroke
				(width 0.1)
				(type default)
			)
			(layer "B.Fab")
		)
		(fp_line
			(start 0.12065 -0.2794)
			(end -0.12065 -0.2794)
			(stroke
				(width 0.1)
				(type default)
			)
			(layer "B.Fab")
		)
		(fp_line
			(start 0.12065 -0.305054)
			(end 0.12065 -0.2794)
			(stroke
				(width 0.1)
				(type default)
			)
			(layer "B.Fab")
		)
		(fp_line
			(start -0.120396 0.3048)
			(end -0.120396 0.2794)
			(stroke
				(width 0.1)
				(type default)
			)
			(layer "B.Fab")
		)
		(fp_line
			(start -0.120396 0.2794)
			(end 0.12065 0.2794)
			(stroke
				(width 0.1)
				(type default)
			)
			(layer "B.Fab")
		)
		(fp_line
			(start -0.12065 -0.2794)
			(end -0.12065 -0.3048)
			(stroke
				(width 0.1)
				(type default)
			)
			(layer "B.Fab")
		)
		(fp_line
			(start -0.12065 -0.3048)
			(end -0.67945 -0.3048)
			(stroke
				(width 0.1)
				(type default)
			)
			(layer "B.Fab")
		)
		(fp_line
			(start -0.67945 0.3048)
			(end -0.120396 0.3048)
			(stroke
				(width 0.1)
				(type default)
			)
			(layer "B.Fab")
		)
		(fp_line
			(start -0.67945 -0.3048)
			(end -0.67945 0.3048)
			(stroke
				(width 0.1)
				(type default)
			)
			(layer "B.Fab")
		)
		(pad "1" smd circle
			(at 0.40005 0)
			(size 0 0)
			(layers "B.Cu" "B.Mask" "B.Paste")
			(net "P1V2_AUX")
		)
		(pad "2" smd circle
			(at -0.40005 0)
			(size 0 0)
			(layers "B.Cu" "B.Mask" "B.Paste")
			(net "GND")
		)
	)
	(footprint ""
		(layer "B.Cu")
		(at 81.106264 -386.766562 90)
		(property "Reference" "C330"
			(at 0 0 90)
			(layer "B.SilkS")
			(hide yes)
			(effects
				(font
					(size 1.27 1.27)
				)
				(justify mirror)
			)
		)
		(property "Value" ""
			(at 0 0 90)
			(layer "B.Fab")
			(effects
				(font
					(size 1.27 1.27)
				)
				(justify mirror)
			)
		)
		(duplicate_pad_numbers_are_jumpers no)
		(fp_line
			(start 0.299974 -0.150114)
			(end -0.299974 -0.150114)
			(stroke
				(width 0.1)
				(type default)
			)
			(layer "B.Fab")
		)
		(fp_line
			(start -0.299974 -0.150114)
			(end -0.299974 0.150114)
			(stroke
				(width 0.1)
				(type default)
			)
			(layer "B.Fab")
		)
		(fp_line
			(start 0.299974 0.150114)
			(end 0.299974 -0.150114)
			(stroke
				(width 0.1)
				(type default)
			)
			(layer "B.Fab")
		)
		(fp_line
			(start -0.299974 0.150114)
			(end 0.299974 0.150114)
			(stroke
				(width 0.1)
				(type default)
			)
			(layer "B.Fab")
		)
		(pad "1" smd rect
			(at 0.2667 0 270)
			(size 0.3048 0.381)
			(layers "B.Cu" "B.Mask" "B.Paste")
			(net "P0V9_CPU1_RT1_2A")
		)
		(pad "2" smd rect
			(at -0.2667 0 270)
			(size 0.3048 0.381)
			(layers "B.Cu" "B.Mask" "B.Paste")
			(net "GND")
		)
	)
	(footprint ""
		(layer "B.Cu")
		(at 406.618948 -398.942052 90)
		(property "Reference" "C796"
			(at 0 0 90)
			(layer "B.SilkS")
			(hide yes)
			(effects
				(font
					(size 1.27 1.27)
				)
				(justify mirror)
			)
		)
		(property "Value" ""
			(at 0 0 90)
			(layer "B.Fab")
			(effects
				(font
					(size 1.27 1.27)
				)
				(justify mirror)
			)
		)
		(duplicate_pad_numbers_are_jumpers no)
		(fp_line
			(start 0.7874 -0.4064)
			(end -0.7874 -0.4064)
			(stroke
				(width 0.1524)
				(type default)
			)
			(layer "B.SilkS")
		)
		(fp_line
			(start -0.7874 -0.4064)
			(end -0.7874 0.4064)
			(stroke
				(width 0.1524)
				(type default)
			)
			(layer "B.SilkS")
		)
		(fp_line
			(start 0.7874 0.4064)
			(end 0.7874 -0.4064)
			(stroke
				(width 0.1524)
				(type default)
			)
			(layer "B.SilkS")
		)
		(fp_line
			(start -0.7874 0.4064)
			(end 0.7874 0.4064)
			(stroke
				(width 0.1524)
				(type default)
			)
			(layer "B.SilkS")
		)
		(fp_line
			(start 0.67945 -0.305054)
			(end 0.12065 -0.305054)
			(stroke
				(width 0.1)
				(type default)
			)
			(layer "B.Fab")
		)
		(fp_line
			(start 0.12065 -0.305054)
			(end 0.12065 -0.2794)
			(stroke
				(width 0.1)
				(type default)
			)
			(layer "B.Fab")
		)
		(fp_line
			(start -0.12065 -0.3048)
			(end -0.67945 -0.3048)
			(stroke
				(width 0.1)
				(type default)
			)
			(layer "B.Fab")
		)
		(fp_line
			(start -0.67945 -0.3048)
			(end -0.67945 0.3048)
			(stroke
				(width 0.1)
				(type default)
			)
			(layer "B.Fab")
		)
		(fp_line
			(start 0.12065 -0.2794)
			(end -0.12065 -0.2794)
			(stroke
				(width 0.1)
				(type default)
			)
			(layer "B.Fab")
		)
		(fp_line
			(start -0.12065 -0.2794)
			(end -0.12065 -0.3048)
			(stroke
				(width 0.1)
				(type default)
			)
			(layer "B.Fab")
		)
		(fp_line
			(start 0.12065 0.2794)
			(end 0.12065 0.3048)
			(stroke
				(width 0.1)
				(type default)
			)
			(layer "B.Fab")
		)
		(fp_line
			(start -0.120396 0.2794)
			(end 0.12065 0.2794)
			(stroke
				(width 0.1)
				(type default)
			)
			(layer "B.Fab")
		)
		(fp_line
			(start 0.67945 0.3048)
			(end 0.67945 -0.305054)
			(stroke
				(width 0.1)
				(type default)
			)
			(layer "B.Fab")
		)
		(fp_line
			(start 0.12065 0.3048)
			(end 0.67945 0.3048)
			(stroke
				(width 0.1)
				(type default)
			)
			(layer "B.Fab")
		)
		(fp_line
			(start -0.120396 0.3048)
			(end -0.120396 0.2794)
			(stroke
				(width 0.1)
				(type default)
			)
			(layer "B.Fab")
		)
		(fp_line
			(start -0.67945 0.3048)
			(end -0.120396 0.3048)
			(stroke
				(width 0.1)
				(type default)
			)
			(layer "B.Fab")
		)
		(pad "1" smd circle
			(at 0.40005 0 270)
			(size 0 0)
			(layers "B.Cu" "B.Mask" "B.Paste")
			(net "P0V9_CPU0_RT2_2A")
		)
		(pad "2" smd circle
			(at -0.40005 0 270)
			(size 0 0)
			(layers "B.Cu" "B.Mask" "B.Paste")
			(net "GND")
		)
	)
	(footprint ""
		(layer "B.Cu")
		(at 78.159864 -11.26871 -90)
		(property "Reference" "R3165"
			(at 0 0 90)
			(layer "B.SilkS")
			(hide yes)
			(effects
				(font
					(size 1.27 1.27)
				)
				(justify mirror)
			)
		)
		(property "Value" ""
			(at 0 0 90)
			(layer "B.Fab")
			(effects
				(font
					(size 1.27 1.27)
				)
				(justify mirror)
			)
		)
		(duplicate_pad_numbers_are_jumpers no)
		(fp_line
			(start -0.7874 0.4064)
			(end 0.7874 0.4064)
			(stroke
				(width 0.1524)
				(type default)
			)
			(layer "B.SilkS")
		)
		(fp_line
			(start 0.7874 0.4064)
			(end 0.7874 -0.4064)
			(stroke
				(width 0.1524)
				(type default)
			)
			(layer "B.SilkS")
		)
		(fp_line
			(start -0.7874 -0.4064)
			(end -0.7874 0.4064)
			(stroke
				(width 0.1524)
				(type default)
			)
			(layer "B.SilkS")
		)
		(fp_line
			(start 0.7874 -0.4064)
			(end -0.7874 -0.4064)
			(stroke
				(width 0.1524)
				(type default)
			)
			(layer "B.SilkS")
		)
		(fp_line
			(start -0.67945 0.3048)
			(end -0.120396 0.3048)
			(stroke
				(width 0.1)
				(type default)
			)
			(layer "B.Fab")
		)
		(fp_line
			(start -0.120396 0.3048)
			(end -0.120396 0.2794)
			(stroke
				(width 0.1)
				(type default)
			)
			(layer "B.Fab")
		)
		(fp_line
			(start 0.12065 0.3048)
			(end 0.67945 0.3048)
			(stroke
				(width 0.1)
				(type default)
			)
			(layer "B.Fab")
		)
		(fp_line
			(start 0.67945 0.3048)
			(end 0.67945 -0.305054)
			(stroke
				(width 0.1)
				(type default)
			)
			(layer "B.Fab")
		)
		(fp_line
			(start -0.120396 0.2794)
			(end 0.12065 0.2794)
			(stroke
				(width 0.1)
				(type default)
			)
			(layer "B.Fab")
		)
		(fp_line
			(start 0.12065 0.2794)
			(end 0.12065 0.3048)
			(stroke
				(width 0.1)
				(type default)
			)
			(layer "B.Fab")
		)
		(fp_line
			(start -0.12065 -0.2794)
			(end -0.12065 -0.3048)
			(stroke
				(width 0.1)
				(type default)
			)
			(layer "B.Fab")
		)
		(fp_line
			(start 0.12065 -0.2794)
			(end -0.12065 -0.2794)
			(stroke
				(width 0.1)
				(type default)
			)
			(layer "B.Fab")
		)
		(fp_line
			(start -0.67945 -0.3048)
			(end -0.67945 0.3048)
			(stroke
				(width 0.1)
				(type default)
			)
			(layer "B.Fab")
		)
		(fp_line
			(start -0.12065 -0.3048)
			(end -0.67945 -0.3048)
			(stroke
				(width 0.1)
				(type default)
			)
			(layer "B.Fab")
		)
		(fp_line
			(start 0.12065 -0.305054)
			(end 0.12065 -0.2794)
			(stroke
				(width 0.1)
				(type default)
			)
			(layer "B.Fab")
		)
		(fp_line
			(start 0.67945 -0.305054)
			(end 0.12065 -0.305054)
			(stroke
				(width 0.1)
				(type default)
			)
			(layer "B.Fab")
		)
		(pad "1" smd circle
			(at 0.40005 0 90)
			(size 0 0)
			(layers "B.Cu" "B.Mask" "B.Paste")
			(net "GND")
		)
		(pad "2" smd circle
			(at -0.40005 0 90)
			(size 0 0)
			(layers "B.Cu" "B.Mask" "B.Paste")
			(net "OCP_V3_2_MAIN_PWR_EN")
		)
	)
)
